Altium Designer Pick and Place Locations
C:\Users\<user>\Desktop\WorkNotes\Projects\PTP\Time-Appliance-Project-master\Time-Card\GNSS\UBlox\RCB-F9T\Altium\ECAD\Project Outputs for GPS_MODULE_ZED-F9T-00B\Pick Place for GPS_MODULE_ZED-F9T(V1I1).txt

========================================================================================================================
File Design Information:

Date:       21/12/22
Time:       09:03
Revision:   Not in VersionControl
Variant:    V1I1
Units used: mil

Designator Comment                   Layer    Footprint                      Center-X(mil) Center-Y(mil) Rotation Description                                                                                 
R14        1k                        TopLayer FP-RMCF0402-MFG                830.000       482.000       180      "1kO ±1% 0.063W 0402 Thick Film Chip Resistor AEC-Q200 compliant"                           
R13        1k                        TopLayer FP-RMCF0402-MFG                831.000       693.000       180      "1kO ±1% 0.063W 0402 Thick Film Chip Resistor AEC-Q200 compliant"                           
R3         1k                        TopLayer FP-RMCF0402-MFG                2124.000      666.000       90       "1kO ±1% 0.063W 0402 Thick Film Chip Resistor AEC-Q200 compliant"                           
R2         1k                        TopLayer FP-RMCF0402-MFG                2201.000      666.000       90       "1kO ±1% 0.063W 0402 Thick Film Chip Resistor AEC-Q200 compliant"                           
DS1        Lumex_SML-LXFM0603SUGCTR  TopLayer LEDS160X80X110-2N_LXFM0603-GR  2491.000      813.000       270      "LED, GREEN, 574NM, 20MA, 20MCD MIN, 2.5VF MAX, 0603, 1.10MM T"                             
R4         10k                       TopLayer FP-RMCF0402-IPC_C              2399.000      777.806       90       "10kO ±1% 0.063W 0402 Thick Film Chip Resistor AEC-Q200 compliant"                          
U3         SN74LVC3G07DCUR           TopLayer DCU0008A_N                     780.000       583.000       0        "Triple Buffer/Driver With Open-Drain Output, DCU0008A, LARGE T&R"                          
C4         Murata_GRM155R61E105KA12D TopLayer CAPC1005X055N                  1635.000      655.000       0        "CAP, CER, X5R, 1UF, 10%, 25V, 0402, 0.55MM T"                                              
C1         Murata_GRM155R61E105KA12D TopLayer CAPC1005X055N                  1635.000      460.000       0        "CAP, CER, X5R, 1UF, 10%, 25V, 0402, 0.55MM T"                                              
U4         LPV511MGX/NOPB            TopLayer DCK0005A_N                     610.000       645.000       90       "micropower Rail-to-Rail Input and Output Operational Amplifier, 5-pin SC-70, Pb-Free"      
U2         SN74LVC3G07DCUR           TopLayer DCU0008A_N                     2006.000      497.000       270      "Triple Buffer/Driver With Open-Drain Output, DCU0008A, LARGE T&R"                          
U1         ZED-F9T-00B               TopLayer GPS_ZED-F9T                    1251.693      538.661       270      "Multi-band GNSS Receiver with Nanosecond-level Timing Accuracy"                            
TP8        SMT_100DIA                TopLayer TP001V_SMT_100DIA              1745.000      150.000       90       "TEST POINT, PC, SMT, 1.00MM DIA"                                                           
TP7        SMT_100DIA                TopLayer TP001V_SMT_100DIA              1690.000      150.000       90       "TEST POINT, PC, SMT, 1.00MM DIA"                                                           
TP6        SMT_100DIA                TopLayer TP001V_SMT_100DIA              1635.000      150.000       90       "TEST POINT, PC, SMT, 1.00MM DIA"                                                           
TP5        SMT_100DIA                TopLayer TP001V_SMT_100DIA              1405.000      1015.000      90       "TEST POINT, PC, SMT, 1.00MM DIA"                                                           
TP4        SMT_100DIA                TopLayer TP001V_SMT_100DIA              1460.000      1015.000      90       "TEST POINT, PC, SMT, 1.00MM DIA"                                                           
TP3        SMT_100DIA                TopLayer TP001V_SMT_100DIA              1055.000      1015.000      90       "TEST POINT, PC, SMT, 1.00MM DIA"                                                           
TP2        SMT_100DIA                TopLayer TP001V_SMT_100DIA              1110.000      1015.000      90       "TEST POINT, PC, SMT, 1.00MM DIA"                                                           
TP1        SMT_100DIA                TopLayer TP001V_SMT_100DIA              1165.000      1015.000      90       "TEST POINT, PC, SMT, 1.00MM DIA"                                                           
R12        Vishay_RCP0603W25R0GEB    TopLayer RESC1608X055N                  515.000       490.000       90       "RES, 25 OHM, 2%, 1.5W, 150PPM/C, 0603"                                                     
R11        100k                      TopLayer FP-RMCF0402-IPC_C              690.000       460.000       180      "100kO ±1% 0.063W 0402 Thick Film Chip Resistor AEC-Q200 compliant"                         
R10        1k                        TopLayer FP-RMCF0402-MFG                615.000       460.000       180      "1kO ±1% 0.063W 0402 Thick Film Chip Resistor AEC-Q200 compliant"                           
R9         100k                      TopLayer FP-RMCF0402-IPC_C              620.000       181.801       0        "100kO ±1% 0.063W 0402 Thick Film Chip Resistor AEC-Q200 compliant"                         
R8         10k                       TopLayer FP-RMCF0402-IPC_C              2081.323      130.806       270      "10kO ±1% 0.063W 0402 Thick Film Chip Resistor AEC-Q200 compliant"                          
R7         10k                       TopLayer FP-RMCF0402-IPC_C              1924.000      130.806       270      "10kO ±1% 0.063W 0402 Thick Film Chip Resistor AEC-Q200 compliant"                          
R1         1k                        TopLayer FP-RMCF0402-MFG                1335.000      1025.000      90       "1kO ±1% 0.063W 0402 Thick Film Chip Resistor AEC-Q200 compliant"                           
Q1         onsemi_NTR2101PT1G        TopLayer SOT23_3pins_300x140x112        595.000       305.000       0        "MOSFET, P-CH, 8VDS, 3.7A ID, 0.052 OHM RDS(ON)@4.5VGS/3.5A, SOT-23-3"                      
L1         "47nH 300mA"              TopLayer FP-LQG15HH_02-IPC_B            515.000       755.000       90       "Multilayer type RF Inductor 47nH ±5% 0.72O 300mA 0402"                                     
J2         SMB_131-3711-301          TopLayer CONN_131-3711-301              222.956       777.123       270      "Rf Coaxial Board Mount Connector"                                                          
J1         NRPN042MAMS-RC            TopLayer NRPN042MAMS-RC                 2404.331      444.094       180      "Dual Row 8 Position 2 mm Pitch Surface Mount Header"                                       
DS3        Lumex_SML-LXFM0603SUGCTR  TopLayer LEDS160X80X110-2N_LXFM0603-GR  2159.000      166.000       90       "LED, GREEN, 574NM, 20MA, 20MCD MIN, 2.5VF MAX, 0603, 1.10MM T"                             
DS2        Lumex_SML-LXFM0603SUGCTR  TopLayer LEDS160X80X110-2N_LXFM0603-GR  2001.677      166.000       90       "LED, GREEN, 574NM, 20MA, 20MCD MIN, 2.5VF MAX, 0603, 1.10MM T"                             
D1         PESD0402-140              TopLayer FP-PESD0402-MFG                430.000       745.000       90       "TVS DIODE 14V 40V 0402"                                                                    
C10        10nF                      TopLayer FP-GRM033-0_03-IPC_B           500.000       650.000       180      "Chip Multilayer Ceramic Capacitors for General Purpose, 0201, 10000pF, X7R, 15%, 10%, 16V" 
C9         100nF                     TopLayer FP-0402-L_1_0_0_05-W_0_5-IPC_B 744.760       690.894       180      None                                                                                        
C8         100nF                     TopLayer FP-0402-L_1_0_0_05-W_0_5-IPC_B 765.000       776.000       180      None                                                                                        
C7         100nF                     TopLayer FP-0402-L_1_0_0_05-W_0_5-IPC_B 590.000       535.000       180      None                                                                                        
C6         100nF                     TopLayer FP-0402-L_1_0_0_05-W_0_5-IPC_B 2121.767      434.000       0        None                                                                                        
C5         Murata_GRM155R61E105KA12D TopLayer CAPC1005X055N                  1275.000      1025.000      90       "CAP, CER, X5R, 1UF, 10%, 25V, 0402, 0.55MM T"                                              
C3         Murata_GRM155R61E105KA12D TopLayer CAPC1005X055N                  1635.000      600.000       0        "CAP, CER, X5R, 1UF, 10%, 25V, 0402, 0.55MM T"                                              
C2         Murata_GRM155R61E105KA12D TopLayer CAPC1005X055N                  1635.000      515.000       0        "CAP, CER, X5R, 1UF, 10%, 25V, 0402, 0.55MM T"                                              
